# T6G (Grand Teton) — schematic netlist excerpt (pin names and nets, part order shuffled) for the footprints in the layout excerpt that follows; sources: Cadence DE-HDL packaged netlist, KiCad conversion of 04192023_DAF0TMB3IC0_F0TG_MB_C_brd_V02_OCP.brd

C2667  Q_CAP  22UF 4V 20% X6S  pkg C0402  page 75 : A = PVDD18_S5_P1 ; B = GND
C821  Q_CAP_DIFFBUS  DIFF BUS_0.22UF 6.3V 20% X6S  pkg C0201  page 65 : \1\ = P5E_CPU1_P0_TX_C_DP<8> ; \2\ = P5E_CPU1_P0_TX_DP<8>
PR6623  Q_RES  5.6 1% CHIP  pkg 0402LF  page 365 : A = SW_P0V9_RETIMER_CPU1_BOOT1 ; B = SW_P0V9_RETIMER_CPU1_BOOT1_RC

(kicad_pcb
	(version 20260206)
	(generator "pcbnew")
	(generator_version "10.0")
	(general
		(thickness 1.6)
		(legacy_teardrops no)
	)
	(paper "A4")
	(title_block
		(title "04192023_DAF0TMB3IC0_F0TG_MB_C_brd_V02_OCP.brd")
		(comment 1 "Grand Teton / footprints 2035-2038 of 8354")
	)
	(layers
		(0 "F.Cu" signal "TOP")
		(4 "In1.Cu" signal "GND")
		(6 "In2.Cu" signal "IN1")
		(8 "In3.Cu" signal "GND1")
		(10 "In4.Cu" signal "IN2")
		(12 "In5.Cu" signal "GND2")
		(14 "In6.Cu" signal "IN3")
		(16 "In7.Cu" signal "GND3")
		(18 "In8.Cu" signal "VCC")
		(20 "In9.Cu" signal "VCC1")
		(22 "In10.Cu" signal "GND4")
		(24 "In11.Cu" signal "IN4")
		(26 "In12.Cu" signal "GND5")
		(28 "In13.Cu" signal "IN5")
		(30 "In14.Cu" signal "GND6")
		(32 "In15.Cu" signal "IN6")
		(34 "In16.Cu" signal "GND7")
		(2 "B.Cu" signal "BOTTOM")
		(9 "F.Adhes" user "F.Adhesive")
		(11 "B.Adhes" user "B.Adhesive")
		(13 "F.Paste" user "Package Geometry/Pastemask Top")
		(15 "B.Paste" user "Package Geometry/Pastemask Bottom")
		(5 "F.SilkS" user "Ref Des/Silkscreen Top")
		(7 "B.SilkS" user "Ref Des/Silkscreen Bottom")
		(1 "F.Mask" user "Board Geometry/Soldermask Top")
		(3 "B.Mask" user "Board Geometry/Soldermask Bottom")
		(17 "Dwgs.User" user "User.Drawings")
		(19 "Cmts.User" user "User.Comments")
		(21 "Eco1.User" user "User.Eco1")
		(23 "Eco2.User" user "User.Eco2")
		(25 "Edge.Cuts" user "Board Geometry/Outline")
		(27 "Margin" user)
		(31 "F.CrtYd" user "Package Geometry/Place Bound Top")
		(29 "B.CrtYd" user "Package Geometry/Place Bound Bottom")
		(35 "F.Fab" user "Ref Des/Assembly Top")
		(33 "B.Fab" user "Ref Des/Assembly Bottom")
	)
	(footprint ""
		(layer "F.Cu")
		(at 17.467072 -393.394184 90)
		(property "Reference" "PR6623"
			(at 0 0 90)
			(layer "F.SilkS")
			(hide yes)
			(effects
				(font
					(size 1.27 1.27)
				)
			)
		)
		(property "Value" ""
			(at 0 0 90)
			(layer "F.Fab")
			(effects
				(font
					(size 1.27 1.27)
				)
			)
		)
		(duplicate_pad_numbers_are_jumpers no)
		(fp_line
			(start 0.7874 -0.4064)
			(end 0.7874 0.4064)
			(stroke
				(width 0.1524)
				(type default)
			)
			(layer "F.SilkS")
		)
		(fp_line
			(start -0.7874 -0.4064)
			(end 0.7874 -0.4064)
			(stroke
				(width 0.1524)
				(type default)
			)
			(layer "F.SilkS")
		)
		(fp_line
			(start 0.7874 0.4064)
			(end -0.7874 0.4064)
			(stroke
				(width 0.1524)
				(type default)
			)
			(layer "F.SilkS")
		)
		(fp_line
			(start -0.7874 0.4064)
			(end -0.7874 -0.4064)
			(stroke
				(width 0.1524)
				(type default)
			)
			(layer "F.SilkS")
		)
		(fp_line
			(start -0.12065 -0.305054)
			(end -0.12065 -0.2794)
			(stroke
				(width 0.1)
				(type default)
			)
			(layer "F.Fab")
		)
		(fp_line
			(start -0.67945 -0.305054)
			(end -0.12065 -0.305054)
			(stroke
				(width 0.1)
				(type default)
			)
			(layer "F.Fab")
		)
		(fp_line
			(start 0.67945 -0.3048)
			(end 0.67945 0.3048)
			(stroke
				(width 0.1)
				(type default)
			)
			(layer "F.Fab")
		)
		(fp_line
			(start 0.12065 -0.3048)
			(end 0.67945 -0.3048)
			(stroke
				(width 0.1)
				(type default)
			)
			(layer "F.Fab")
		)
		(fp_line
			(start 0.12065 -0.2794)
			(end 0.12065 -0.3048)
			(stroke
				(width 0.1)
				(type default)
			)
			(layer "F.Fab")
		)
		(fp_line
			(start -0.12065 -0.2794)
			(end 0.12065 -0.2794)
			(stroke
				(width 0.1)
				(type default)
			)
			(layer "F.Fab")
		)
		(fp_line
			(start 0.120396 0.2794)
			(end -0.12065 0.2794)
			(stroke
				(width 0.1)
				(type default)
			)
			(layer "F.Fab")
		)
		(fp_line
			(start -0.12065 0.2794)
			(end -0.12065 0.3048)
			(stroke
				(width 0.1)
				(type default)
			)
			(layer "F.Fab")
		)
		(fp_line
			(start 0.67945 0.3048)
			(end 0.120396 0.3048)
			(stroke
				(width 0.1)
				(type default)
			)
			(layer "F.Fab")
		)
		(fp_line
			(start 0.120396 0.3048)
			(end 0.120396 0.2794)
			(stroke
				(width 0.1)
				(type default)
			)
			(layer "F.Fab")
		)
		(fp_line
			(start -0.12065 0.3048)
			(end -0.67945 0.3048)
			(stroke
				(width 0.1)
				(type default)
			)
			(layer "F.Fab")
		)
		(fp_line
			(start -0.67945 0.3048)
			(end -0.67945 -0.305054)
			(stroke
				(width 0.1)
				(type default)
			)
			(layer "F.Fab")
		)
		(pad "1" smd circle
			(at -0.40005 0 90)
			(size 0 0)
			(layers "F.Cu" "F.Mask" "F.Paste")
			(net "SW_P0V9_RETIMER_CPU1_BOOT1")
		)
		(pad "2" smd circle
			(at 0.40005 0 90)
			(size 0 0)
			(layers "F.Cu" "F.Mask" "F.Paste")
			(net "SW_P0V9_RETIMER_CPU1_BOOT1_RC")
		)
	)
	(footprint ""
		(layer "F.Cu")
		(at 37.220906 19.444716 -90)
		(property "Reference" "U25_SRM"
			(at 0 0 270)
			(layer "F.SilkS")
			(hide yes)
			(effects
				(font
					(size 1.27 1.27)
				)
			)
		)
		(property "Value" ""
			(at 0 0 270)
			(layer "F.Fab")
			(effects
				(font
					(size 1.27 1.27)
				)
			)
		)
		(duplicate_pad_numbers_are_jumpers no)
		(pad "1" smd circle
			(at 0 0 270)
			(size 0.762 0.762)
			(layers "F.Cu" "F.Mask" "F.Paste")
			(net "Net_10788")
		)
	)
	(footprint ""
		(layer "F.Cu")
		(at 105.960164 -256.505456)
		(property "Reference" "C2667"
			(at 0 0 0)
			(layer "F.SilkS")
			(hide yes)
			(effects
				(font
					(size 1.27 1.27)
				)
			)
		)
		(property "Value" ""
			(at 0 0 0)
			(layer "F.Fab")
			(effects
				(font
					(size 1.27 1.27)
				)
			)
		)
		(duplicate_pad_numbers_are_jumpers no)
		(fp_line
			(start -0.7874 -0.4064)
			(end 0.7874 -0.4064)
			(stroke
				(width 0.1524)
				(type default)
			)
			(layer "F.SilkS")
		)
		(fp_line
			(start -0.7874 0.4064)
			(end -0.7874 -0.4064)
			(stroke
				(width 0.1524)
				(type default)
			)
			(layer "F.SilkS")
		)
		(fp_line
			(start 0.7874 -0.4064)
			(end 0.7874 0.4064)
			(stroke
				(width 0.1524)
				(type default)
			)
			(layer "F.SilkS")
		)
		(fp_line
			(start 0.7874 0.4064)
			(end -0.7874 0.4064)
			(stroke
				(width 0.1524)
				(type default)
			)
			(layer "F.SilkS")
		)
		(fp_line
			(start -0.67945 -0.305054)
			(end -0.12065 -0.305054)
			(stroke
				(width 0.1)
				(type default)
			)
			(layer "F.Fab")
		)
		(fp_line
			(start -0.67945 0.3048)
			(end -0.67945 -0.305054)
			(stroke
				(width 0.1)
				(type default)
			)
			(layer "F.Fab")
		)
		(fp_line
			(start -0.12065 -0.305054)
			(end -0.12065 -0.2794)
			(stroke
				(width 0.1)
				(type default)
			)
			(layer "F.Fab")
		)
		(fp_line
			(start -0.12065 -0.2794)
			(end 0.12065 -0.2794)
			(stroke
				(width 0.1)
				(type default)
			)
			(layer "F.Fab")
		)
		(fp_line
			(start -0.12065 0.2794)
			(end -0.12065 0.3048)
			(stroke
				(width 0.1)
				(type default)
			)
			(layer "F.Fab")
		)
		(fp_line
			(start -0.12065 0.3048)
			(end -0.67945 0.3048)
			(stroke
				(width 0.1)
				(type default)
			)
			(layer "F.Fab")
		)
		(fp_line
			(start 0.120396 0.2794)
			(end -0.12065 0.2794)
			(stroke
				(width 0.1)
				(type default)
			)
			(layer "F.Fab")
		)
		(fp_line
			(start 0.120396 0.3048)
			(end 0.120396 0.2794)
			(stroke
				(width 0.1)
				(type default)
			)
			(layer "F.Fab")
		)
		(fp_line
			(start 0.12065 -0.3048)
			(end 0.67945 -0.3048)
			(stroke
				(width 0.1)
				(type default)
			)
			(layer "F.Fab")
		)
		(fp_line
			(start 0.12065 -0.2794)
			(end 0.12065 -0.3048)
			(stroke
				(width 0.1)
				(type default)
			)
			(layer "F.Fab")
		)
		(fp_line
			(start 0.67945 -0.3048)
			(end 0.67945 0.3048)
			(stroke
				(width 0.1)
				(type default)
			)
			(layer "F.Fab")
		)
		(fp_line
			(start 0.67945 0.3048)
			(end 0.120396 0.3048)
			(stroke
				(width 0.1)
				(type default)
			)
			(layer "F.Fab")
		)
		(pad "1" smd circle
			(at -0.40005 0)
			(size 0 0)
			(layers "F.Cu" "F.Mask" "F.Paste")
			(net "PVDD18_S5_P1")
		)
		(pad "2" smd circle
			(at 0.40005 0)
			(size 0 0)
			(layers "F.Cu" "F.Mask" "F.Paste")
			(net "GND")
		)
	)
	(footprint ""
		(layer "F.Cu")
		(at 56.604154 -373.03583 -90)
		(property "Reference" "C821"
			(at 0 0 270)
			(layer "F.SilkS")
			(hide yes)
			(effects
				(font
					(size 1.27 1.27)
				)
			)
		)
		(property "Value" ""
			(at 0 0 270)
			(layer "F.Fab")
			(effects
				(font
					(size 1.27 1.27)
				)
			)
		)
		(duplicate_pad_numbers_are_jumpers no)
		(fp_line
			(start -0.299974 0.150114)
			(end -0.299974 -0.150114)
			(stroke
				(width 0.1)
				(type default)
			)
			(layer "F.Fab")
		)
		(fp_line
			(start 0.299974 0.150114)
			(end -0.299974 0.150114)
			(stroke
				(width 0.1)
				(type default)
			)
			(layer "F.Fab")
		)
		(fp_line
			(start -0.299974 -0.150114)
			(end 0.299974 -0.150114)
			(stroke
				(width 0.1)
				(type default)
			)
			(layer "F.Fab")
		)
		(fp_line
			(start 0.299974 -0.150114)
			(end 0.299974 0.150114)
			(stroke
				(width 0.1)
				(type default)
			)
			(layer "F.Fab")
		)
		(pad "1" smd rect
			(at -0.2667 0 270)
			(size 0.3048 0.381)
			(layers "F.Cu" "F.Mask" "F.Paste")
			(net "P5E_CPU1_P0_TX_C_DP<8>")
		)
		(pad "2" smd rect
			(at 0.2667 0 270)
			(size 0.3048 0.381)
			(layers "F.Cu" "F.Mask" "F.Paste")
			(net "P5E_CPU1_P0_TX_DP<8>")
		)
	)
)
